# S9S_MB_2U (Grand Teton) — schematic netlist excerpt (pin names and nets, part order shuffled) for the footprints in the layout excerpt that follows; sources: Cadence DE-HDL packaged netlist, KiCad conversion of 03242023_DA0F0TMBIJ0_F0T_Motherboard_J_brd_V01_OCP.brd

PC204_P0_1  Q_CAP  22UF 4V 20% X6S  pkg C0805  page 275 : A = PVCCINFAON_CPU0 ; B = GND
R3117  Q_RES  510K 5% EMPTY  pkg 0402LF  page 259 : A = P12V_AUX ; B = P3V3_AUX_EN
C501  Q_CAP  47UF 4V 20% X6S  pkg C0805  page 75 : A = PVCCFA_EHV_FIVRA_CPU0 ; B = GND

(kicad_pcb
	(version 20260206)
	(generator "pcbnew")
	(generator_version "10.0")
	(general
		(thickness 1.6)
		(legacy_teardrops no)
	)
	(paper "A4")
	(title_block
		(title "03242023_DA0F0TMBIJ0_F0T_Motherboard_J_brd_V01_OCP.brd")
		(comment 1 "Grand Teton / footprints 5391-5393 of 6105")
	)
	(layers
		(0 "F.Cu" signal "TOP")
		(4 "In1.Cu" signal "GND")
		(6 "In2.Cu" signal "IN1")
		(8 "In3.Cu" signal "GND1")
		(10 "In4.Cu" signal "IN2")
		(12 "In5.Cu" signal "GND2")
		(14 "In6.Cu" signal "IN3")
		(16 "In7.Cu" signal "GND3")
		(18 "In8.Cu" signal "VCC")
		(20 "In9.Cu" signal "VCC1")
		(22 "In10.Cu" signal "GND4")
		(24 "In11.Cu" signal "IN4")
		(26 "In12.Cu" signal "GND5")
		(28 "In13.Cu" signal "IN5")
		(30 "In14.Cu" signal "GND6")
		(32 "In15.Cu" signal "IN6")
		(34 "In16.Cu" signal "GND7")
		(2 "B.Cu" signal "BOTTOM")
		(9 "F.Adhes" user "F.Adhesive")
		(11 "B.Adhes" user "B.Adhesive")
		(13 "F.Paste" user "Package Geometry/Pastemask Top")
		(15 "B.Paste" user "Package Geometry/Pastemask Bottom")
		(5 "F.SilkS" user "Ref Des/Silkscreen Top")
		(7 "B.SilkS" user "Ref Des/Silkscreen Bottom")
		(1 "F.Mask" user "Board Geometry/Soldermask Top")
		(3 "B.Mask" user "Board Geometry/Soldermask Bottom")
		(17 "Dwgs.User" user "User.Drawings")
		(19 "Cmts.User" user "User.Comments")
		(21 "Eco1.User" user "User.Eco1")
		(23 "Eco2.User" user "User.Eco2")
		(25 "Edge.Cuts" user "Board Geometry/Outline")
		(27 "Margin" user)
		(31 "F.CrtYd" user "Package Geometry/Place Bound Top")
		(29 "B.CrtYd" user "Package Geometry/Place Bound Bottom")
		(35 "F.Fab" user "Ref Des/Assembly Top")
		(33 "B.Fab" user "Ref Des/Assembly Bottom")
	)
	(footprint ""
		(layer "B.Cu")
		(at 353.619308 -259.531866 90)
		(property "Reference" "C501"
			(at 0 0 90)
			(layer "B.SilkS")
			(hide yes)
			(effects
				(font
					(size 1.27 1.27)
				)
				(justify mirror)
			)
		)
		(property "Value" ""
			(at 0 0 90)
			(layer "B.Fab")
			(effects
				(font
					(size 1.27 1.27)
				)
				(justify mirror)
			)
		)
		(duplicate_pad_numbers_are_jumpers no)
		(fp_line
			(start 1.524 -0.762)
			(end -1.524 -0.762)
			(stroke
				(width 0.1524)
				(type default)
			)
			(layer "B.SilkS")
		)
		(fp_line
			(start -1.524 -0.762)
			(end -1.524 0.762)
			(stroke
				(width 0.1524)
				(type default)
			)
			(layer "B.SilkS")
		)
		(fp_line
			(start 1.524 0.762)
			(end 1.524 -0.762)
			(stroke
				(width 0.1524)
				(type default)
			)
			(layer "B.SilkS")
		)
		(fp_line
			(start -1.524 0.762)
			(end 1.524 0.762)
			(stroke
				(width 0.1524)
				(type default)
			)
			(layer "B.SilkS")
		)
		(fp_line
			(start 1.1049 -0.724916)
			(end 1.1049 0.724916)
			(stroke
				(width 0.1)
				(type default)
			)
			(layer "B.Fab")
		)
		(fp_line
			(start -1.1049 -0.724916)
			(end 1.1049 -0.724916)
			(stroke
				(width 0.1)
				(type default)
			)
			(layer "B.Fab")
		)
		(fp_line
			(start 1.1049 0.724916)
			(end -1.1049 0.724916)
			(stroke
				(width 0.1)
				(type default)
			)
			(layer "B.Fab")
		)
		(fp_line
			(start -1.1049 0.724916)
			(end -1.1049 -0.724916)
			(stroke
				(width 0.1)
				(type default)
			)
			(layer "B.Fab")
		)
		(pad "1" smd rect
			(at 0.889 0 90)
			(size 1.016 1.27)
			(layers "B.Cu" "B.Mask" "B.Paste")
			(net "PVCCFA_EHV_FIVRA_CPU0")
		)
		(pad "2" smd rect
			(at -0.889 0 90)
			(size 1.016 1.27)
			(layers "B.Cu" "B.Mask" "B.Paste")
			(net "GND")
		)
	)
	(footprint ""
		(layer "B.Cu")
		(at 407.91257 -167.350948 180)
		(property "Reference" "PC204_P0_1"
			(at 0 0 0)
			(layer "B.SilkS")
			(hide yes)
			(effects
				(font
					(size 1.27 1.27)
				)
				(justify mirror)
			)
		)
		(property "Value" ""
			(at 0 0 0)
			(layer "B.Fab")
			(effects
				(font
					(size 1.27 1.27)
				)
				(justify mirror)
			)
		)
		(duplicate_pad_numbers_are_jumpers no)
		(fp_line
			(start 1.524 0.762)
			(end 1.524 -0.762)
			(stroke
				(width 0.1524)
				(type default)
			)
			(layer "B.SilkS")
		)
		(fp_line
			(start 1.524 -0.762)
			(end -1.524 -0.762)
			(stroke
				(width 0.1524)
				(type default)
			)
			(layer "B.SilkS")
		)
		(fp_line
			(start -1.524 0.762)
			(end 1.524 0.762)
			(stroke
				(width 0.1524)
				(type default)
			)
			(layer "B.SilkS")
		)
		(fp_line
			(start -1.524 -0.762)
			(end -1.524 0.762)
			(stroke
				(width 0.1524)
				(type default)
			)
			(layer "B.SilkS")
		)
		(fp_line
			(start 1.1049 0.724916)
			(end -1.1049 0.724916)
			(stroke
				(width 0.1)
				(type default)
			)
			(layer "B.Fab")
		)
		(fp_line
			(start 1.1049 -0.724916)
			(end 1.1049 0.724916)
			(stroke
				(width 0.1)
				(type default)
			)
			(layer "B.Fab")
		)
		(fp_line
			(start -1.1049 0.724916)
			(end -1.1049 -0.724916)
			(stroke
				(width 0.1)
				(type default)
			)
			(layer "B.Fab")
		)
		(fp_line
			(start -1.1049 -0.724916)
			(end 1.1049 -0.724916)
			(stroke
				(width 0.1)
				(type default)
			)
			(layer "B.Fab")
		)
		(pad "1" smd rect
			(at 0.889 0 180)
			(size 1.016 1.27)
			(layers "B.Cu" "B.Mask" "B.Paste")
			(net "PVCCINFAON_CPU0")
		)
		(pad "2" smd rect
			(at -0.889 0 180)
			(size 1.016 1.27)
			(layers "B.Cu" "B.Mask" "B.Paste")
			(net "GND")
		)
	)
	(footprint ""
		(layer "B.Cu")
		(at 448.22872 -78.115668 90)
		(property "Reference" "R3117"
			(at 0 0 90)
			(layer "B.SilkS")
			(hide yes)
			(effects
				(font
					(size 1.27 1.27)
				)
				(justify mirror)
			)
		)
		(property "Value" ""
			(at 0 0 90)
			(layer "B.Fab")
			(effects
				(font
					(size 1.27 1.27)
				)
				(justify mirror)
			)
		)
		(duplicate_pad_numbers_are_jumpers no)
		(fp_line
			(start 0.7874 -0.4064)
			(end -0.7874 -0.4064)
			(stroke
				(width 0.1524)
				(type default)
			)
			(layer "B.SilkS")
		)
		(fp_line
			(start -0.7874 -0.4064)
			(end -0.7874 0.4064)
			(stroke
				(width 0.1524)
				(type default)
			)
			(layer "B.SilkS")
		)
		(fp_line
			(start 0.7874 0.4064)
			(end 0.7874 -0.4064)
			(stroke
				(width 0.1524)
				(type default)
			)
			(layer "B.SilkS")
		)
		(fp_line
			(start -0.7874 0.4064)
			(end 0.7874 0.4064)
			(stroke
				(width 0.1524)
				(type default)
			)
			(layer "B.SilkS")
		)
		(fp_line
			(start 0.67945 -0.305054)
			(end 0.12065 -0.305054)
			(stroke
				(width 0.1)
				(type default)
			)
			(layer "B.Fab")
		)
		(fp_line
			(start 0.12065 -0.305054)
			(end 0.12065 -0.2794)
			(stroke
				(width 0.1)
				(type default)
			)
			(layer "B.Fab")
		)
		(fp_line
			(start -0.12065 -0.3048)
			(end -0.67945 -0.3048)
			(stroke
				(width 0.1)
				(type default)
			)
			(layer "B.Fab")
		)
		(fp_line
			(start -0.67945 -0.3048)
			(end -0.67945 0.3048)
			(stroke
				(width 0.1)
				(type default)
			)
			(layer "B.Fab")
		)
		(fp_line
			(start 0.12065 -0.2794)
			(end -0.12065 -0.2794)
			(stroke
				(width 0.1)
				(type default)
			)
			(layer "B.Fab")
		)
		(fp_line
			(start -0.12065 -0.2794)
			(end -0.12065 -0.3048)
			(stroke
				(width 0.1)
				(type default)
			)
			(layer "B.Fab")
		)
		(fp_line
			(start 0.12065 0.2794)
			(end 0.12065 0.3048)
			(stroke
				(width 0.1)
				(type default)
			)
			(layer "B.Fab")
		)
		(fp_line
			(start -0.120396 0.2794)
			(end 0.12065 0.2794)
			(stroke
				(width 0.1)
				(type default)
			)
			(layer "B.Fab")
		)
		(fp_line
			(start 0.67945 0.3048)
			(end 0.67945 -0.305054)
			(stroke
				(width 0.1)
				(type default)
			)
			(layer "B.Fab")
		)
		(fp_line
			(start 0.12065 0.3048)
			(end 0.67945 0.3048)
			(stroke
				(width 0.1)
				(type default)
			)
			(layer "B.Fab")
		)
		(fp_line
			(start -0.120396 0.3048)
			(end -0.120396 0.2794)
			(stroke
				(width 0.1)
				(type default)
			)
			(layer "B.Fab")
		)
		(fp_line
			(start -0.67945 0.3048)
			(end -0.120396 0.3048)
			(stroke
				(width 0.1)
				(type default)
			)
			(layer "B.Fab")
		)
		(pad "1" smd circle
			(at 0.40005 0 270)
			(size 0 0)
			(layers "B.Cu" "B.Mask" "B.Paste")
			(net "P12V_AUX")
		)
		(pad "2" smd circle
			(at -0.40005 0 270)
			(size 0 0)
			(layers "B.Cu" "B.Mask" "B.Paste")
			(net "P3V3_AUX_EN")
		)
	)
)
